(kicad_pcb
	(version 20260206)
	(generator "pcbnew")
	(generator_version "10.0")
	(general
		(thickness 1.59074)
		(legacy_teardrops no)
	)
	(paper "A4")
	(title_block
		(title "osc-sa45 — FAB_SA45_DaughterCard.PcbDoc")
		(comment 1 "Time Appliance Project (Time Card) / footprints 14-22 of 44")
	)
	(layers
		(0 "F.Cu" signal "L01-Top Layer")
		(4 "In1.Cu" signal "L02-Inner Layer")
		(6 "In2.Cu" signal "L03-Inner Layer")
		(2 "B.Cu" signal "L04-Bottom Layer")
		(9 "F.Adhes" user "F.Adhesive")
		(11 "B.Adhes" user "B.Adhesive")
		(13 "F.Paste" user "Top Paste")
		(15 "B.Paste" user "Bottom Paste")
		(5 "F.SilkS" user "Top Overlay")
		(7 "B.SilkS" user "Bottom Overlay")
		(1 "F.Mask" user "Top Solder")
		(3 "B.Mask" user "Bottom Solder")
		(17 "Dwgs.User" user "User.Drawings")
		(19 "Cmts.User" user "User.Comments")
		(21 "Eco1.User" user "User.Eco1")
		(23 "Eco2.User" user "User.Eco2")
		(25 "Edge.Cuts" user)
		(27 "Margin" user)
		(31 "F.CrtYd" user "Top Courtyard")
		(29 "B.CrtYd" user "Bottom Courtyard")
		(35 "F.Fab" user "Top Component Outline")
		(33 "B.Fab" user "Bottom Component Outline 2")
	)
	(footprint "FAB_SA45_DaughterCard:Keystone_4871"
		(locked yes)
		(layer "B.Cu")
		(at 132.561105 123.343605 180)
		(property "Reference" "J3"
			(at -4.076845 0.18071 0)
			(unlocked yes)
			(layer "B.SilkS")
			(effects
				(font
					(face "Arial")
					(size 0.63 0.63)
					(thickness 0.254)
				)
				(justify mirror)
			)
		)
		(property "Value" "Keystone_4871"
			(at 6.3343 -5.019802 0)
			(unlocked yes)
			(layer "B.SilkS")
			(hide yes)
			(effects
				(font
					(size 1.524 1.524)
					(thickness 0.254)
				)
				(justify mirror)
			)
		)
		(sheetname "SCH_SA45_DaughterCard")
		(sheetfile "SCH_SA45_DaughterCard.kicad_sch")
		(duplicate_pad_numbers_are_jumpers no)
		(fp_line
			(start 3.4 3.4)
			(end -3.4 3.4)
			(stroke
				(width 0.1)
				(type solid)
			)
			(layer "B.CrtYd")
		)
		(fp_line
			(start 3.4 -3.4)
			(end 3.4 3.4)
			(stroke
				(width 0.1)
				(type solid)
			)
			(layer "B.CrtYd")
		)
		(fp_line
			(start 3.4 -3.4)
			(end -3.4 -3.4)
			(stroke
				(width 0.1)
				(type solid)
			)
			(layer "B.CrtYd")
		)
		(fp_line
			(start -3.4 -0.8)
			(end -3.4 3.4)
			(stroke
				(width 0.1)
				(type solid)
			)
			(layer "B.CrtYd")
		)
		(fp_line
			(start -3.4 -3.4)
			(end -3.4 -0.8)
			(stroke
				(width 0.1)
				(type solid)
			)
			(layer "B.CrtYd")
		)
		(fp_text user ""
			(at 0.367795 0.63446 360)
			(unlocked yes)
			(layer "B.Fab")
			(effects
				(font
					(face "Arial")
					(size 0.63 0.63)
					(thickness 0.254)
				)
				(justify mirror)
			)
		)
		(fp_text user "${REFERENCE}"
			(at -0.001845 0.19946 360)
			(unlocked yes)
			(layer "B.Fab")
			(effects
				(font
					(face "Arial")
					(size 0.63 0.63)
					(thickness 0.254)
				)
				(justify mirror)
			)
		)
		(pad "Hole" thru_hole circle
			(at 0 0 180)
			(size 0 0)
			(drill 3.7)
			(layers "*.Cu" "*.Mask")
			(remove_unused_layers no)
			(thermal_bridge_angle 90)
		)
		(pad "MT" smd circle
			(at 0 0 180)
			(size 6.2 6.2)
			(layers "B.Cu" "B.Mask" "B.Paste")
			(solder_mask_margin 0.05)
			(thermal_bridge_angle 90)
		)
	)
	(footprint "Vault:CAPC2013X145N"
		(layer "B.Cu")
		(at 144.976105 115.553605)
		(property "Reference" "C5"
			(at -2.69615 -0.12655 0)
			(unlocked yes)
			(layer "B.SilkS")
			(effects
				(font
					(face "Arial")
					(size 0.63 0.63)
					(thickness 0.254)
				)
				(justify mirror)
			)
		)
		(property "Value" "Murata_GRM21BR6YA106KE43L"
			(at -22.39585 -6.2605 0)
			(unlocked yes)
			(layer "B.SilkS")
			(hide yes)
			(effects
				(font
					(face "Arial")
					(size 0.63 0.63)
					(thickness 0.254)
				)
				(justify mirror)
			)
		)
		(sheetname "SCH_SA45_DaughterCard")
		(sheetfile "SCH_SA45_DaughterCard.kicad_sch")
		(duplicate_pad_numbers_are_jumpers no)
		(fp_line
			(start -1.8 -1.1)
			(end 1.8 -1.1)
			(stroke
				(width 0.1)
				(type solid)
			)
			(layer "B.CrtYd")
		)
		(fp_line
			(start -1.8 1.1)
			(end -1.8 -1.1)
			(stroke
				(width 0.1)
				(type solid)
			)
			(layer "B.CrtYd")
		)
		(fp_line
			(start -1.8 1.1)
			(end 1.8 1.1)
			(stroke
				(width 0.1)
				(type solid)
			)
			(layer "B.CrtYd")
		)
		(fp_line
			(start 1.8 1.1)
			(end 1.8 -1.1)
			(stroke
				(width 0.1)
				(type solid)
			)
			(layer "B.CrtYd")
		)
		(fp_line
			(start -1 -0.65)
			(end 1 -0.65)
			(stroke
				(width 0.05)
				(type solid)
			)
			(layer "B.Fab")
		)
		(fp_line
			(start -1 0.65)
			(end -1 -0.65)
			(stroke
				(width 0.05)
				(type solid)
			)
			(layer "B.Fab")
		)
		(fp_line
			(start -1 0.65)
			(end 1 0.65)
			(stroke
				(width 0.05)
				(type solid)
			)
			(layer "B.Fab")
		)
		(fp_line
			(start 1 0.65)
			(end 1 -0.65)
			(stroke
				(width 0.05)
				(type solid)
			)
			(layer "B.Fab")
		)
		(fp_text_box "${REFERENCE}"
			(start 1.14717 0.20754)
			(end -1.14713 -0.20759)
			(margins 0 0 0 0)
			(angle 180)
			(layer "B.Fab")
			(effects
				(font
					(face "Arial")
					(size 0.315 0.315)
					(thickness 0.254)
				)
				(justify top mirror)
			)
			(border no)
			(stroke
				(width 0.1)
				(type default)
			)
			(knockout no)
		)
		(pad "1" smd rect
			(at -0.9 0)
			(size 1.3 1.65)
			(layers "B.Cu" "B.Mask" "B.Paste")
			(net "+5V")
			(solder_mask_margin 0.05)
			(solder_paste_margin 0)
		)
		(pad "2" smd rect
			(at 0.9 0)
			(size 1.3 1.65)
			(layers "B.Cu" "B.Mask" "B.Paste")
			(net "GND")
			(solder_mask_margin 0.05)
			(solder_paste_margin 0)
		)
	)
	(footprint "FAB_SA45_DaughterCard:Eaton_HCM0703-4R7-R"
		(layer "B.Cu")
		(at 151.576105 108.491105)
		(property "Reference" "L1"
			(at 5.124995 -0.06267 0)
			(unlocked yes)
			(layer "B.SilkS")
			(effects
				(font
					(face "Arial")
					(size 0.63 0.63)
					(thickness 0.254)
				)
				(justify mirror)
			)
		)
		(property "Value" "4.7uH"
			(at -1.46809 3.72341 0)
			(unlocked yes)
			(layer "B.SilkS")
			(hide yes)
			(effects
				(font
					(face "Arial")
					(size 0.63 0.63)
					(thickness 0.254)
				)
				(justify mirror)
			)
		)
		(sheetname "SCH_SA45_DaughterCard")
		(sheetfile "SCH_SA45_DaughterCard.kicad_sch")
		(duplicate_pad_numbers_are_jumpers no)
		(fp_line
			(start -4 -3.5)
			(end 4 -3.5)
			(stroke
				(width 0.1)
				(type solid)
			)
			(layer "B.CrtYd")
		)
		(fp_line
			(start -4 -0.8)
			(end -4 -3.5)
			(stroke
				(width 0.1)
				(type solid)
			)
			(layer "B.CrtYd")
		)
		(fp_line
			(start -4 3.5)
			(end -4 -0.8)
			(stroke
				(width 0.1)
				(type solid)
			)
			(layer "B.CrtYd")
		)
		(fp_line
			(start -4 3.5)
			(end 4 3.5)
			(stroke
				(width 0.1)
				(type solid)
			)
			(layer "B.CrtYd")
		)
		(fp_line
			(start 4 3.5)
			(end 4 -3.5)
			(stroke
				(width 0.1)
				(type solid)
			)
			(layer "B.CrtYd")
		)
		(fp_text user "${REFERENCE}"
			(at -0.000005 0.19391 180)
			(unlocked yes)
			(layer "B.Fab")
			(effects
				(font
					(face "Arial")
					(size 0.63 0.63)
					(thickness 0.254)
				)
				(justify mirror)
			)
		)
		(fp_text user ""
			(at 0.367795 0.63446 180)
			(unlocked yes)
			(layer "B.Fab")
			(effects
				(font
					(face "Arial")
					(size 0.63 0.63)
					(thickness 0.254)
				)
				(justify mirror)
			)
		)
		(pad "1" smd rect
			(at -2.65 0)
			(size 2.3 3.3)
			(layers "B.Cu" "B.Mask" "B.Paste")
			(net "SW")
			(solder_mask_margin 0.05)
			(solder_paste_margin 0)
		)
		(pad "2" smd rect
			(at 2.65 0)
			(size 2.3 3.3)
			(layers "B.Cu" "B.Mask" "B.Paste")
			(net "+3.3V")
			(solder_mask_margin 0.05)
			(solder_paste_margin 0)
		)
	)
	(footprint "Vault:TH001V_109DIA_000mt_8600-0"
		(layer "B.Cu")
		(at 168.841105 125.343605 180)
		(property "Reference" "P1"
			(at 0 1.96517 0)
			(unlocked yes)
			(layer "B.SilkS")
			(effects
				(font
					(face "Arial")
					(size 0.63 0.63)
					(thickness 0.254)
				)
				(justify mirror)
			)
		)
		(property "Value" "Mill-Max_8600-0-05-80-00-00-03-0"
			(at 22.534825 -2.89778 0)
			(unlocked yes)
			(layer "B.SilkS")
			(hide yes)
			(effects
				(font
					(face "Arial")
					(size 0.63 0.63)
					(thickness 0.254)
				)
				(justify mirror)
			)
		)
		(sheetname "SCH_SA45_DaughterCard")
		(sheetfile "SCH_SA45_DaughterCard.kicad_sch")
		(duplicate_pad_numbers_are_jumpers no)
		(fp_line
			(start 1.4 1.4)
			(end -1.4 1.4)
			(stroke
				(width 0.1)
				(type solid)
			)
			(layer "B.CrtYd")
		)
		(fp_line
			(start 1.4 -1.4)
			(end 1.4 1.4)
			(stroke
				(width 0.1)
				(type solid)
			)
			(layer "B.CrtYd")
		)
		(fp_line
			(start 1.4 -1.4)
			(end -1.4 -1.4)
			(stroke
				(width 0.1)
				(type solid)
			)
			(layer "B.CrtYd")
		)
		(fp_line
			(start -1.4 -1.4)
			(end -1.4 1.4)
			(stroke
				(width 0.1)
				(type solid)
			)
			(layer "B.CrtYd")
		)
		(fp_circle
			(center 0 0)
			(end 0 0.545)
			(stroke
				(width 0.1)
				(type solid)
			)
			(fill no)
			(layer "B.Fab")
		)
		(fp_text user "${REFERENCE}"
			(at 0 0.159211 360)
			(unlocked yes)
			(layer "B.Fab")
			(effects
				(font
					(face "Arial")
					(size 0.8001 0.8001)
					(thickness 0.254)
				)
				(justify mirror)
			)
		)
		(pad "1" thru_hole circle
			(at 0.04 0 180)
			(size 2.09 2.09)
			(drill 1.09)
			(layers "*.Cu" "*.Mask")
			(remove_unused_layers no)
			(net "NC")
			(solder_mask_margin 0.05)
			(solder_paste_margin -2147.48364)
			(thermal_bridge_angle 90)
		)
	)
	(footprint "FAB_SA45_DaughterCard:Keystone_4871"
		(locked yes)
		(layer "B.Cu")
		(at 164.361105 85.243605 180)
		(property "Reference" "J5"
			(at 3.97315 0.1321 0)
			(unlocked yes)
			(layer "B.SilkS")
			(effects
				(font
					(face "Arial")
					(size 0.63 0.63)
					(thickness 0.254)
				)
				(justify mirror)
			)
		)
		(property "Value" "Keystone_4871"
			(at 6.3343 -5.019802 0)
			(unlocked yes)
			(layer "B.SilkS")
			(hide yes)
			(effects
				(font
					(size 1.524 1.524)
					(thickness 0.254)
				)
				(justify mirror)
			)
		)
		(sheetname "SCH_SA45_DaughterCard")
		(sheetfile "SCH_SA45_DaughterCard.kicad_sch")
		(duplicate_pad_numbers_are_jumpers no)
		(fp_line
			(start 3.4 3.4)
			(end -3.4 3.4)
			(stroke
				(width 0.1)
				(type solid)
			)
			(layer "B.CrtYd")
		)
		(fp_line
			(start 3.4 -3.4)
			(end 3.4 3.4)
			(stroke
				(width 0.1)
				(type solid)
			)
			(layer "B.CrtYd")
		)
		(fp_line
			(start 3.4 -3.4)
			(end -3.4 -3.4)
			(stroke
				(width 0.1)
				(type solid)
			)
			(layer "B.CrtYd")
		)
		(fp_line
			(start -3.4 -0.8)
			(end -3.4 3.4)
			(stroke
				(width 0.1)
				(type solid)
			)
			(layer "B.CrtYd")
		)
		(fp_line
			(start -3.4 -3.4)
			(end -3.4 -0.8)
			(stroke
				(width 0.1)
				(type solid)
			)
			(layer "B.CrtYd")
		)
		(fp_text user ""
			(at 0.367795 0.63446 360)
			(unlocked yes)
			(layer "B.Fab")
			(effects
				(font
					(face "Arial")
					(size 0.63 0.63)
					(thickness 0.254)
				)
				(justify mirror)
			)
		)
		(fp_text user "${REFERENCE}"
			(at -0.00185 0.20085 360)
			(unlocked yes)
			(layer "B.Fab")
			(effects
				(font
					(face "Arial")
					(size 0.63 0.63)
					(thickness 0.254)
				)
				(justify mirror)
			)
		)
		(pad "Hole" thru_hole circle
			(at 0 0 180)
			(size 0 0)
			(drill 3.7)
			(layers "*.Cu" "*.Mask")
			(remove_unused_layers no)
			(thermal_bridge_angle 90)
		)
		(pad "MT" smd circle
			(at 0 0 180)
			(size 6.2 6.2)
			(layers "B.Cu" "B.Mask" "B.Paste")
			(solder_mask_margin 0.05)
			(thermal_bridge_angle 90)
		)
	)
	(footprint "Vault:TH001V_109DIA_000mt_8600-0"
		(layer "B.Cu")
		(at 136.335105 81.993605 180)
		(property "Reference" "P8"
			(at 0 -1.93857 0)
			(unlocked yes)
			(layer "B.SilkS")
			(effects
				(font
					(face "Arial")
					(size 0.63 0.63)
					(thickness 0.254)
				)
				(justify mirror)
			)
		)
		(property "Value" "Mill-Max_8600-0-05-80-00-00-03-0"
			(at 22.534825 -2.89778 0)
			(unlocked yes)
			(layer "B.SilkS")
			(hide yes)
			(effects
				(font
					(face "Arial")
					(size 0.63 0.63)
					(thickness 0.254)
				)
				(justify mirror)
			)
		)
		(sheetname "SCH_SA45_DaughterCard")
		(sheetfile "SCH_SA45_DaughterCard.kicad_sch")
		(duplicate_pad_numbers_are_jumpers no)
		(fp_line
			(start 1.4 1.4)
			(end -1.4 1.4)
			(stroke
				(width 0.1)
				(type solid)
			)
			(layer "B.CrtYd")
		)
		(fp_line
			(start 1.4 -1.4)
			(end 1.4 1.4)
			(stroke
				(width 0.1)
				(type solid)
			)
			(layer "B.CrtYd")
		)
		(fp_line
			(start 1.4 -1.4)
			(end -1.4 -1.4)
			(stroke
				(width 0.1)
				(type solid)
			)
			(layer "B.CrtYd")
		)
		(fp_line
			(start -1.4 -1.4)
			(end -1.4 1.4)
			(stroke
				(width 0.1)
				(type solid)
			)
			(layer "B.CrtYd")
		)
		(fp_circle
			(center 0 0)
			(end 0 0.545)
			(stroke
				(width 0.1)
				(type solid)
			)
			(fill no)
			(layer "B.Fab")
		)
		(fp_text user "${REFERENCE}"
			(at 0 0.166251 360)
			(unlocked yes)
			(layer "B.Fab")
			(effects
				(font
					(face "Arial")
					(size 0.8001 0.8001)
					(thickness 0.254)
				)
				(justify mirror)
			)
		)
		(pad "1" thru_hole circle
			(at 0 -0.02 180)
			(size 2.09 2.09)
			(drill 1.09)
			(layers "*.Cu" "*.Mask")
			(remove_unused_layers no)
			(net "RX")
			(solder_mask_margin 0.05)
			(solder_paste_margin -2147.48364)
			(thermal_bridge_angle 90)
		)
	)
	(footprint "Vault:TH001V_109DIA_000mt_8600-0"
		(layer "B.Cu")
		(at 128.161105 84.663605 180)
		(property "Reference" "P4"
			(at 0 -1.71351 0)
			(unlocked yes)
			(layer "B.SilkS")
			(effects
				(font
					(face "Arial")
					(size 0.63 0.63)
					(thickness 0.254)
				)
				(justify mirror)
			)
		)
		(property "Value" "Mill-Max_8600-0-05-80-00-00-03-0"
			(at 22.534825 -2.89778 0)
			(unlocked yes)
			(layer "B.SilkS")
			(hide yes)
			(effects
				(font
					(face "Arial")
					(size 0.63 0.63)
					(thickness 0.254)
				)
				(justify mirror)
			)
		)
		(sheetname "SCH_SA45_DaughterCard")
		(sheetfile "SCH_SA45_DaughterCard.kicad_sch")
		(duplicate_pad_numbers_are_jumpers no)
		(fp_line
			(start 1.4 1.4)
			(end -1.4 1.4)
			(stroke
				(width 0.1)
				(type solid)
			)
			(layer "B.CrtYd")
		)
		(fp_line
			(start 1.4 -1.4)
			(end 1.4 1.4)
			(stroke
				(width 0.1)
				(type solid)
			)
			(layer "B.CrtYd")
		)
		(fp_line
			(start 1.4 -1.4)
			(end -1.4 -1.4)
			(stroke
				(width 0.1)
				(type solid)
			)
			(layer "B.CrtYd")
		)
		(fp_line
			(start -1.4 -1.4)
			(end -1.4 1.4)
			(stroke
				(width 0.1)
				(type solid)
			)
			(layer "B.CrtYd")
		)
		(fp_circle
			(center 0 0)
			(end 0 0.545)
			(stroke
				(width 0.1)
				(type solid)
			)
			(fill no)
			(layer "B.Fab")
		)
		(fp_text user "${REFERENCE}"
			(at 0 0.160971 360)
			(unlocked yes)
			(layer "B.Fab")
			(effects
				(font
					(face "Arial")
					(size 0.8001 0.8001)
					(thickness 0.254)
				)
				(justify mirror)
			)
		)
		(pad "1" thru_hole circle
			(at 0 -0.04 180)
			(size 2.09 2.09)
			(drill 1.09)
			(layers "*.Cu" "*.Mask")
			(remove_unused_layers no)
			(net "GND")
			(solder_mask_margin 0.05)
			(solder_paste_margin -2147.48364)
			(thermal_bridge_angle 90)
		)
	)
	(footprint "Vault:TH001V_109DIA_000mt_8600-0"
		(layer "B.Cu")
		(at 128.161105 125.343605 180)
		(property "Reference" "P5"
			(at 0 2.1471 0)
			(unlocked yes)
			(layer "B.SilkS")
			(effects
				(font
					(face "Arial")
					(size 0.63 0.63)
					(thickness 0.254)
				)
				(justify mirror)
			)
		)
		(property "Value" "Mill-Max_8600-0-05-80-00-00-03-0"
			(at 22.534825 -2.89778 0)
			(unlocked yes)
			(layer "B.SilkS")
			(hide yes)
			(effects
				(font
					(face "Arial")
					(size 0.63 0.63)
					(thickness 0.254)
				)
				(justify mirror)
			)
		)
		(sheetname "SCH_SA45_DaughterCard")
		(sheetfile "SCH_SA45_DaughterCard.kicad_sch")
		(duplicate_pad_numbers_are_jumpers no)
		(fp_line
			(start 1.4 1.4)
			(end -1.4 1.4)
			(stroke
				(width 0.1)
				(type solid)
			)
			(layer "B.CrtYd")
		)
		(fp_line
			(start 1.4 -1.4)
			(end 1.4 1.4)
			(stroke
				(width 0.1)
				(type solid)
			)
			(layer "B.CrtYd")
		)
		(fp_line
			(start 1.4 -1.4)
			(end -1.4 -1.4)
			(stroke
				(width 0.1)
				(type solid)
			)
			(layer "B.CrtYd")
		)
		(fp_line
			(start -1.4 -1.4)
			(end -1.4 1.4)
			(stroke
				(width 0.1)
				(type solid)
			)
			(layer "B.CrtYd")
		)
		(fp_circle
			(center 0 0)
			(end 0 0.545)
			(stroke
				(width 0.1)
				(type solid)
			)
			(fill no)
			(layer "B.Fab")
		)
		(fp_text user "${REFERENCE}"
			(at 0.000005 0.168011 360)
			(unlocked yes)
			(layer "B.Fab")
			(effects
				(font
					(face "Arial")
					(size 0.8001 0.8001)
					(thickness 0.254)
				)
				(justify mirror)
			)
		)
		(pad "1" thru_hole circle
			(at 0 0 180)
			(size 2.09 2.09)
			(drill 1.09)
			(layers "*.Cu" "*.Mask")
			(remove_unused_layers no)
			(net "+5V")
			(solder_mask_margin 0.05)
			(solder_paste_margin -2147.48364)
			(thermal_bridge_angle 90)
		)
	)
	(footprint "Vault:RESC1005X040N"
		(layer "B.Cu")
		(at 142.546105 107.328605 180)
		(property "Reference" "R4"
			(at 2.32 0.12263 0)
			(unlocked yes)
			(layer "B.SilkS")
			(effects
				(font
					(face "Arial")
					(size 0.63 0.63)
					(thickness 0.254)
				)
				(justify mirror)
			)
		)
		(property "Value" "Yageo_RC0402FR-0730KL"
			(at 5.42454 -8.62942 0)
			(unlocked yes)
			(layer "B.SilkS")
			(hide yes)
			(effects
				(font
					(face "Arial")
					(size 0.63 0.63)
					(thickness 0.254)
				)
				(justify mirror)
			)
		)
		(sheetname "SCH_SA45_DaughterCard")
		(sheetfile "SCH_SA45_DaughterCard.kicad_sch")
		(duplicate_pad_numbers_are_jumpers no)
		(fp_line
			(start 0.95 0.5)
			(end -0.95 0.5)
			(stroke
				(width 0.1)
				(type solid)
			)
			(layer "B.CrtYd")
		)
		(fp_line
			(start 0.95 -0.5)
			(end 0.95 0.5)
			(stroke
				(width 0.1)
				(type solid)
			)
			(layer "B.CrtYd")
		)
		(fp_line
			(start 0.95 -0.5)
			(end -0.95 -0.5)
			(stroke
				(width 0.1)
				(type solid)
			)
			(layer "B.CrtYd")
		)
		(fp_line
			(start -0.95 -0.5)
			(end -0.95 0.5)
			(stroke
				(width 0.1)
				(type solid)
			)
			(layer "B.CrtYd")
		)
		(fp_line
			(start 0.5 0.25)
			(end -0.5 0.25)
			(stroke
				(width 0.05)
				(type solid)
			)
			(layer "B.Fab")
		)
		(fp_line
			(start 0.5 -0.25)
			(end 0.5 0.25)
			(stroke
				(width 0.05)
				(type solid)
			)
			(layer "B.Fab")
		)
		(fp_line
			(start 0.5 -0.25)
			(end -0.5 -0.25)
			(stroke
				(width 0.05)
				(type solid)
			)
			(layer "B.Fab")
		)
		(fp_line
			(start -0.5 -0.25)
			(end -0.5 0.25)
			(stroke
				(width 0.05)
				(type solid)
			)
			(layer "B.Fab")
		)
		(fp_text_box "${REFERENCE}"
			(start 1.09004 0.20727)
			(end -1.09004 -0.20726)
			(margins 0 0 0 0)
			(angle -180)
			(layer "B.Fab")
			(effects
				(font
					(face "Arial")
					(size 0.315 0.315)
					(thickness 0.254)
				)
				(justify top mirror)
			)
			(border no)
			(stroke
				(width 0.1)
				(type default)
			)
			(knockout no)
		)
		(pad "1" smd rect
			(at -0.48 0 180)
			(size 0.57 0.62)
			(layers "B.Cu" "B.Mask" "B.Paste")
			(net "NetC4_2")
			(solder_mask_margin 0.05)
			(solder_paste_margin 0)
		)
		(pad "2" smd rect
			(at 0.48 0 180)
			(size 0.57 0.62)
			(layers "B.Cu" "B.Mask" "B.Paste")
			(net "GND")
			(solder_mask_margin 0.05)
			(solder_paste_margin 0)
		)
	)
)
